(kicad_pcb
	(version 20260206)
	(generator "pcbnew")
	(generator_version "10.0")
	(general
		(thickness 1.6)
		(legacy_teardrops no)
	)
	(paper "A4")
	(title_block
		(title "01162023_DA0F0TEBIF0_F0T_Expander_BD_F_brd_V02_OCP.brd")
		(comment 1 "Grand Teton / footprints 2421-2426 of 9728")
	)
	(layers
		(0 "F.Cu" signal "TOP")
		(4 "In1.Cu" signal "GND")
		(6 "In2.Cu" signal "VCC")
		(8 "In3.Cu" signal "VCC1")
		(10 "In4.Cu" signal "GND1")
		(12 "In5.Cu" signal "IN1")
		(14 "In6.Cu" signal "GND2")
		(16 "In7.Cu" signal "IN2")
		(18 "In8.Cu" signal "GND3")
		(20 "In9.Cu" signal "IN3")
		(22 "In10.Cu" signal "GND4")
		(24 "In11.Cu" signal "IN4")
		(26 "In12.Cu" signal "GND5")
		(28 "In13.Cu" signal "IN5")
		(30 "In14.Cu" signal "GND6")
		(32 "In15.Cu" signal "IN6")
		(34 "In16.Cu" signal "GND7")
		(2 "B.Cu" signal "BOTTOM")
		(9 "F.Adhes" user "F.Adhesive")
		(11 "B.Adhes" user "B.Adhesive")
		(13 "F.Paste" user "Package Geometry/Pastemask Top")
		(15 "B.Paste" user "Package Geometry/Pastemask Bottom")
		(5 "F.SilkS" user "Ref Des/Silkscreen Top")
		(7 "B.SilkS" user "Ref Des/Silkscreen Bottom")
		(1 "F.Mask" user "Board Geometry/Soldermask Top")
		(3 "B.Mask" user "Board Geometry/Soldermask Bottom")
		(17 "Dwgs.User" user "User.Drawings")
		(19 "Cmts.User" user "User.Comments")
		(21 "Eco1.User" user "User.Eco1")
		(23 "Eco2.User" user "User.Eco2")
		(25 "Edge.Cuts" user "Board Geometry/Outline")
		(27 "Margin" user)
		(31 "F.CrtYd" user "Package Geometry/Place Bound Top")
		(29 "B.CrtYd" user "Package Geometry/Place Bound Bottom")
		(35 "F.Fab" user "Ref Des/Assembly Top")
		(33 "B.Fab" user "Ref Des/Assembly Bottom")
	)
	(footprint ""
		(layer "F.Cu")
		(at 199.966834 -52.543456 180)
		(property "Reference" "PC536"
			(at 0 0 180)
			(layer "F.SilkS")
			(hide yes)
			(effects
				(font
					(size 1.27 1.27)
				)
			)
		)
		(property "Value" ""
			(at 0 0 180)
			(layer "F.Fab")
			(effects
				(font
					(size 1.27 1.27)
				)
			)
		)
		(duplicate_pad_numbers_are_jumpers no)
		(fp_line
			(start 0.7874 0.4064)
			(end -0.7874 0.4064)
			(stroke
				(width 0.1524)
				(type default)
			)
			(layer "F.SilkS")
		)
		(fp_line
			(start 0.7874 -0.4064)
			(end 0.7874 0.4064)
			(stroke
				(width 0.1524)
				(type default)
			)
			(layer "F.SilkS")
		)
		(fp_line
			(start -0.7874 0.4064)
			(end -0.7874 -0.4064)
			(stroke
				(width 0.1524)
				(type default)
			)
			(layer "F.SilkS")
		)
		(fp_line
			(start -0.7874 -0.4064)
			(end 0.7874 -0.4064)
			(stroke
				(width 0.1524)
				(type default)
			)
			(layer "F.SilkS")
		)
		(fp_line
			(start 0.67945 0.3048)
			(end 0.120396 0.3048)
			(stroke
				(width 0.1)
				(type default)
			)
			(layer "F.Fab")
		)
		(fp_line
			(start 0.67945 -0.3048)
			(end 0.67945 0.3048)
			(stroke
				(width 0.1)
				(type default)
			)
			(layer "F.Fab")
		)
		(fp_line
			(start 0.12065 -0.2794)
			(end 0.12065 -0.3048)
			(stroke
				(width 0.1)
				(type default)
			)
			(layer "F.Fab")
		)
		(fp_line
			(start 0.12065 -0.3048)
			(end 0.67945 -0.3048)
			(stroke
				(width 0.1)
				(type default)
			)
			(layer "F.Fab")
		)
		(fp_line
			(start 0.120396 0.3048)
			(end 0.120396 0.2794)
			(stroke
				(width 0.1)
				(type default)
			)
			(layer "F.Fab")
		)
		(fp_line
			(start 0.120396 0.2794)
			(end -0.12065 0.2794)
			(stroke
				(width 0.1)
				(type default)
			)
			(layer "F.Fab")
		)
		(fp_line
			(start -0.12065 0.3048)
			(end -0.67945 0.3048)
			(stroke
				(width 0.1)
				(type default)
			)
			(layer "F.Fab")
		)
		(fp_line
			(start -0.12065 0.2794)
			(end -0.12065 0.3048)
			(stroke
				(width 0.1)
				(type default)
			)
			(layer "F.Fab")
		)
		(fp_line
			(start -0.12065 -0.2794)
			(end 0.12065 -0.2794)
			(stroke
				(width 0.1)
				(type default)
			)
			(layer "F.Fab")
		)
		(fp_line
			(start -0.12065 -0.305054)
			(end -0.12065 -0.2794)
			(stroke
				(width 0.1)
				(type default)
			)
			(layer "F.Fab")
		)
		(fp_line
			(start -0.67945 0.3048)
			(end -0.67945 -0.305054)
			(stroke
				(width 0.1)
				(type default)
			)
			(layer "F.Fab")
		)
		(fp_line
			(start -0.67945 -0.305054)
			(end -0.12065 -0.305054)
			(stroke
				(width 0.1)
				(type default)
			)
			(layer "F.Fab")
		)
		(pad "1" smd circle
			(at -0.40005 0 180)
			(size 0 0)
			(layers "F.Cu" "F.Mask" "F.Paste")
			(net "P3V3_SSD7")
		)
		(pad "2" smd circle
			(at 0.40005 0 180)
			(size 0 0)
			(layers "F.Cu" "F.Mask" "F.Paste")
			(net "GND")
		)
	)
	(footprint ""
		(layer "F.Cu")
		(at 190.747142 -54.3941)
		(property "Reference" "PU35"
			(at -1.633982 2.792222 0)
			(unlocked yes)
			(layer "F.SilkS")
			(effects
				(font
					(size 0.7874 0.5842)
					(thickness 0.1524)
				)
				(justify left)
			)
		)
		(property "Value" ""
			(at 0 0 0)
			(layer "F.Fab")
			(effects
				(font
					(size 1.27 1.27)
				)
			)
		)
		(duplicate_pad_numbers_are_jumpers no)
		(fp_line
			(start -1.943608 -1.549908)
			(end 1.943608 -1.549908)
			(stroke
				(width 0.1524)
				(type default)
			)
			(layer "F.SilkS")
		)
		(fp_line
			(start -1.943608 1.549908)
			(end -1.943608 -1.549908)
			(stroke
				(width 0.1524)
				(type default)
			)
			(layer "F.SilkS")
		)
		(fp_line
			(start 1.943608 -1.549908)
			(end 1.943608 1.549908)
			(stroke
				(width 0.1524)
				(type default)
			)
			(layer "F.SilkS")
		)
		(fp_line
			(start 1.943608 1.549908)
			(end -1.943608 1.549908)
			(stroke
				(width 0.1524)
				(type default)
			)
			(layer "F.SilkS")
		)
		(fp_poly
			(pts
				(xy -2.019808 -1.549908) (xy -1.257808 -1.549908) (xy -1.257808 -1.880108) (xy -2.019808 -1.880108)
			)
			(stroke
				(width 0)
				(type default)
			)
			(fill yes)
			(layer "F.SilkS")
		)
		(fp_line
			(start -1.549908 -1.549908)
			(end 1.549908 -1.549908)
			(stroke
				(width 0.1)
				(type default)
			)
			(layer "F.Fab")
		)
		(fp_line
			(start -1.549908 1.549908)
			(end -1.549908 -1.549908)
			(stroke
				(width 0.1)
				(type default)
			)
			(layer "F.Fab")
		)
		(fp_line
			(start 1.549908 -1.549908)
			(end 1.549908 1.549908)
			(stroke
				(width 0.1)
				(type default)
			)
			(layer "F.Fab")
		)
		(fp_line
			(start 1.549908 1.549908)
			(end -1.549908 1.549908)
			(stroke
				(width 0.1)
				(type default)
			)
			(layer "F.Fab")
		)
		(fp_poly
			(pts
				(xy -2.019808 -1.549908) (xy -1.257808 -1.549908) (xy -1.257808 -1.880108) (xy -2.019808 -1.880108)
			)
			(stroke
				(width 0)
				(type default)
			)
			(fill yes)
			(layer "F.Fab")
		)
		(pad "1" smd rect
			(at -1.500124 -1.249934 270)
			(size 0.2794 0.6096)
			(layers "F.Cu" "F.Mask" "F.Paste")
			(net "P12V_SSD6_R")
		)
		(pad "2" smd rect
			(at -1.500124 -0.750062 270)
			(size 0.2794 0.6096)
			(layers "F.Cu" "F.Mask" "F.Paste")
			(net "P12V_SSD6_R")
		)
		(pad "3" smd rect
			(at -1.500124 -0.249936 270)
			(size 0.2794 0.6096)
			(layers "F.Cu" "F.Mask" "F.Paste")
			(net "P12V_SSD6_R")
		)
		(pad "4" smd rect
			(at -1.500124 0.249936 270)
			(size 0.2794 0.6096)
			(layers "F.Cu" "F.Mask" "F.Paste")
			(net "P12V_SSD6_R")
		)
		(pad "5" smd rect
			(at -1.500124 0.750062 270)
			(size 0.2794 0.6096)
			(layers "F.Cu" "F.Mask" "F.Paste")
			(net "P12V_SSD6_R")
		)
		(pad "6" smd rect
			(at -1.500124 1.249934 270)
			(size 0.2794 0.6096)
			(layers "F.Cu" "F.Mask" "F.Paste")
			(net "GND")
		)
		(pad "7" smd rect
			(at 1.500124 1.249934 270)
			(size 0.2794 0.6096)
			(layers "F.Cu" "F.Mask" "F.Paste")
			(net "P12V_SSD6_SS")
		)
		(pad "8" smd rect
			(at 1.500124 0.750062 270)
			(size 0.2794 0.6096)
			(layers "F.Cu" "F.Mask" "F.Paste")
			(net "PWRGD_P12V_SSD6")
		)
		(pad "9" smd rect
			(at 1.500124 0.249936 270)
			(size 0.2794 0.6096)
			(layers "F.Cu" "F.Mask" "F.Paste")
			(net "P12V_SSD6_OCP")
		)
		(pad "10" smd rect
			(at 1.500124 -0.249936 270)
			(size 0.2794 0.6096)
			(layers "F.Cu" "F.Mask" "F.Paste")
			(net "P5V_AUX")
		)
		(pad "11" smd rect
			(at 1.500124 -0.750062 270)
			(size 0.2794 0.6096)
			(layers "F.Cu" "F.Mask" "F.Paste")
			(net "SSD6_PWR_EN_R")
		)
		(pad "12" smd rect
			(at 1.500124 -1.249934 270)
			(size 0.2794 0.6096)
			(layers "F.Cu" "F.Mask" "F.Paste")
			(net "P12V_AUX")
		)
		(pad "13" smd rect
			(at 0 0)
			(size 1.9812 2.7178)
			(layers "F.Cu" "F.Mask" "F.Paste")
			(net "P12V_AUX")
		)
		(zone
			(layer "F.Cu")
			(hatch none 0.5)
			(connect_pads
				(clearance 0)
			)
			(min_thickness 0.25)
			(keepout
				(tracks not_allowed)
				(vias allowed)
				(pads allowed)
				(copperpour not_allowed)
				(footprints allowed)
			)
			(placement
				(enabled no)
				(sheetname "")
			)
			(fill
				(thermal_gap 0.5)
				(thermal_bridge_width 0.5)
				(island_removal_mode 0)
			)
			(polygon
				(pts
					(xy 191.890142 -55.9435) (xy 191.890142 -55.8165) (xy 191.890142 -52.8447) (xy 191.890142 -52.844192)
					(xy 189.604142 -52.844192) (xy 189.604142 -52.8447) (xy 189.604142 -52.9717) (xy 189.604142 -54.3941)
					(xy 189.705742 -54.3941) (xy 189.705742 -52.9717) (xy 191.788542 -52.9717) (xy 191.788542 -55.8165)
					(xy 189.705742 -55.8165) (xy 189.705742 -54.4195) (xy 189.604142 -54.4195) (xy 189.604142 -55.8165)
					(xy 189.604142 -55.9435) (xy 189.604142 -55.944008) (xy 191.890142 -55.944008)
				)
			)
		)
	)
	(footprint ""
		(layer "F.Cu")
		(at 223.50476 -317.573914 180)
		(property "Reference" "PC1008"
			(at 0 0 180)
			(layer "F.SilkS")
			(hide yes)
			(effects
				(font
					(size 1.27 1.27)
				)
			)
		)
		(property "Value" ""
			(at 0 0 180)
			(layer "F.Fab")
			(effects
				(font
					(size 1.27 1.27)
				)
			)
		)
		(duplicate_pad_numbers_are_jumpers no)
		(fp_line
			(start 1.524 0.762)
			(end -1.524 0.762)
			(stroke
				(width 0.1524)
				(type default)
			)
			(layer "F.SilkS")
		)
		(fp_line
			(start 1.524 -0.762)
			(end 1.524 0.762)
			(stroke
				(width 0.1524)
				(type default)
			)
			(layer "F.SilkS")
		)
		(fp_line
			(start -1.524 0.762)
			(end -1.524 -0.762)
			(stroke
				(width 0.1524)
				(type default)
			)
			(layer "F.SilkS")
		)
		(fp_line
			(start -1.524 -0.762)
			(end 1.524 -0.762)
			(stroke
				(width 0.1524)
				(type default)
			)
			(layer "F.SilkS")
		)
		(fp_line
			(start 1.1049 0.724916)
			(end 1.1049 -0.724916)
			(stroke
				(width 0.1)
				(type default)
			)
			(layer "F.Fab")
		)
		(fp_line
			(start 1.1049 -0.724916)
			(end -1.1049 -0.724916)
			(stroke
				(width 0.1)
				(type default)
			)
			(layer "F.Fab")
		)
		(fp_line
			(start -1.1049 0.724916)
			(end 1.1049 0.724916)
			(stroke
				(width 0.1)
				(type default)
			)
			(layer "F.Fab")
		)
		(fp_line
			(start -1.1049 -0.724916)
			(end -1.1049 0.724916)
			(stroke
				(width 0.1)
				(type default)
			)
			(layer "F.Fab")
		)
		(pad "1" smd rect
			(at -0.889 0)
			(size 1.016 1.27)
			(layers "F.Cu" "F.Mask" "F.Paste")
			(net "SW_P12V_P1V25_PEX1_FLT")
		)
		(pad "2" smd rect
			(at 0.889 0)
			(size 1.016 1.27)
			(layers "F.Cu" "F.Mask" "F.Paste")
			(net "GND")
		)
	)
	(footprint ""
		(layer "F.Cu")
		(at 268.53515 -82.002122 180)
		(property "Reference" "R1073"
			(at 0 0 180)
			(layer "F.SilkS")
			(hide yes)
			(effects
				(font
					(size 1.27 1.27)
				)
			)
		)
		(property "Value" ""
			(at 0 0 180)
			(layer "F.Fab")
			(effects
				(font
					(size 1.27 1.27)
				)
			)
		)
		(duplicate_pad_numbers_are_jumpers no)
		(fp_line
			(start 0.7874 0.4064)
			(end -0.7874 0.4064)
			(stroke
				(width 0.1524)
				(type default)
			)
			(layer "F.SilkS")
		)
		(fp_line
			(start 0.67945 0.3048)
			(end 0.120396 0.3048)
			(stroke
				(width 0.1)
				(type default)
			)
			(layer "F.Fab")
		)
		(fp_line
			(start 0.67945 -0.3048)
			(end 0.67945 0.3048)
			(stroke
				(width 0.1)
				(type default)
			)
			(layer "F.Fab")
		)
		(fp_line
			(start 0.12065 -0.2794)
			(end 0.12065 -0.3048)
			(stroke
				(width 0.1)
				(type default)
			)
			(layer "F.Fab")
		)
		(fp_line
			(start 0.12065 -0.3048)
			(end 0.67945 -0.3048)
			(stroke
				(width 0.1)
				(type default)
			)
			(layer "F.Fab")
		)
		(fp_line
			(start 0.120396 0.3048)
			(end 0.120396 0.2794)
			(stroke
				(width 0.1)
				(type default)
			)
			(layer "F.Fab")
		)
		(fp_line
			(start 0.120396 0.2794)
			(end -0.12065 0.2794)
			(stroke
				(width 0.1)
				(type default)
			)
			(layer "F.Fab")
		)
		(fp_line
			(start -0.12065 0.3048)
			(end -0.67945 0.3048)
			(stroke
				(width 0.1)
				(type default)
			)
			(layer "F.Fab")
		)
		(fp_line
			(start -0.12065 0.2794)
			(end -0.12065 0.3048)
			(stroke
				(width 0.1)
				(type default)
			)
			(layer "F.Fab")
		)
		(fp_line
			(start -0.12065 -0.2794)
			(end 0.12065 -0.2794)
			(stroke
				(width 0.1)
				(type default)
			)
			(layer "F.Fab")
		)
		(fp_line
			(start -0.12065 -0.305054)
			(end -0.12065 -0.2794)
			(stroke
				(width 0.1)
				(type default)
			)
			(layer "F.Fab")
		)
		(fp_line
			(start -0.67945 0.3048)
			(end -0.67945 -0.305054)
			(stroke
				(width 0.1)
				(type default)
			)
			(layer "F.Fab")
		)
		(fp_line
			(start -0.67945 -0.305054)
			(end -0.12065 -0.305054)
			(stroke
				(width 0.1)
				(type default)
			)
			(layer "F.Fab")
		)
		(pad "1" smd circle
			(at -0.40005 0 180)
			(size 0 0)
			(layers "F.Cu" "F.Mask" "F.Paste")
			(net "CLK_100M_CK440Q_1_DB800ZL_R_DP")
		)
		(pad "2" smd circle
			(at 0.40005 0 180)
			(size 0 0)
			(layers "F.Cu" "F.Mask" "F.Paste")
			(net "CLK_100M_CK440Q_1_DB800ZL_DP")
		)
	)
	(footprint ""
		(layer "F.Cu")
		(at 312.823606 -87.349076 -90)
		(property "Reference" "R301"
			(at 0 0 270)
			(layer "F.SilkS")
			(hide yes)
			(effects
				(font
					(size 1.27 1.27)
				)
			)
		)
		(property "Value" ""
			(at 0 0 270)
			(layer "F.Fab")
			(effects
				(font
					(size 1.27 1.27)
				)
			)
		)
		(duplicate_pad_numbers_are_jumpers no)
		(fp_line
			(start -0.7874 0.4064)
			(end -0.7874 -0.4064)
			(stroke
				(width 0.1524)
				(type default)
			)
			(layer "F.SilkS")
		)
		(fp_line
			(start 0.7874 0.4064)
			(end -0.7874 0.4064)
			(stroke
				(width 0.1524)
				(type default)
			)
			(layer "F.SilkS")
		)
		(fp_line
			(start -0.7874 -0.4064)
			(end 0.7874 -0.4064)
			(stroke
				(width 0.1524)
				(type default)
			)
			(layer "F.SilkS")
		)
		(fp_line
			(start 0.7874 -0.4064)
			(end 0.7874 0.4064)
			(stroke
				(width 0.1524)
				(type default)
			)
			(layer "F.SilkS")
		)
		(fp_line
			(start -0.67945 0.3048)
			(end -0.67945 -0.305054)
			(stroke
				(width 0.1)
				(type default)
			)
			(layer "F.Fab")
		)
		(fp_line
			(start -0.12065 0.3048)
			(end -0.67945 0.3048)
			(stroke
				(width 0.1)
				(type default)
			)
			(layer "F.Fab")
		)
		(fp_line
			(start 0.120396 0.3048)
			(end 0.120396 0.2794)
			(stroke
				(width 0.1)
				(type default)
			)
			(layer "F.Fab")
		)
		(fp_line
			(start 0.67945 0.3048)
			(end 0.120396 0.3048)
			(stroke
				(width 0.1)
				(type default)
			)
			(layer "F.Fab")
		)
		(fp_line
			(start -0.12065 0.2794)
			(end -0.12065 0.3048)
			(stroke
				(width 0.1)
				(type default)
			)
			(layer "F.Fab")
		)
		(fp_line
			(start 0.120396 0.2794)
			(end -0.12065 0.2794)
			(stroke
				(width 0.1)
				(type default)
			)
			(layer "F.Fab")
		)
		(fp_line
			(start -0.12065 -0.2794)
			(end 0.12065 -0.2794)
			(stroke
				(width 0.1)
				(type default)
			)
			(layer "F.Fab")
		)
		(fp_line
			(start 0.12065 -0.2794)
			(end 0.12065 -0.3048)
			(stroke
				(width 0.1)
				(type default)
			)
			(layer "F.Fab")
		)
		(fp_line
			(start 0.12065 -0.3048)
			(end 0.67945 -0.3048)
			(stroke
				(width 0.1)
				(type default)
			)
			(layer "F.Fab")
		)
		(fp_line
			(start 0.67945 -0.3048)
			(end 0.67945 0.3048)
			(stroke
				(width 0.1)
				(type default)
			)
			(layer "F.Fab")
		)
		(fp_line
			(start -0.67945 -0.305054)
			(end -0.12065 -0.305054)
			(stroke
				(width 0.1)
				(type default)
			)
			(layer "F.Fab")
		)
		(fp_line
			(start -0.12065 -0.305054)
			(end -0.12065 -0.2794)
			(stroke
				(width 0.1)
				(type default)
			)
			(layer "F.Fab")
		)
		(pad "1" smd circle
			(at -0.40005 0 270)
			(size 0 0)
			(layers "F.Cu" "F.Mask" "F.Paste")
			(net "RST_NIC5_PERST1_R_N")
		)
		(pad "2" smd circle
			(at 0.40005 0 270)
			(size 0 0)
			(layers "F.Cu" "F.Mask" "F.Paste")
			(net "RST_HP_NIC5_BUF_N")
		)
	)
	(footprint ""
		(layer "F.Cu")
		(at 258.44373 -46.90491)
		(property "Reference" "R596"
			(at 0 0 0)
			(layer "F.SilkS")
			(hide yes)
			(effects
				(font
					(size 1.27 1.27)
				)
			)
		)
		(property "Value" ""
			(at 0 0 0)
			(layer "F.Fab")
			(effects
				(font
					(size 1.27 1.27)
				)
			)
		)
		(duplicate_pad_numbers_are_jumpers no)
		(fp_line
			(start -0.7874 -0.4064)
			(end 0.7874 -0.4064)
			(stroke
				(width 0.1524)
				(type default)
			)
			(layer "F.SilkS")
		)
		(fp_line
			(start -0.7874 0.4064)
			(end -0.7874 -0.4064)
			(stroke
				(width 0.1524)
				(type default)
			)
			(layer "F.SilkS")
		)
		(fp_line
			(start 0.7874 -0.4064)
			(end 0.7874 0.4064)
			(stroke
				(width 0.1524)
				(type default)
			)
			(layer "F.SilkS")
		)
		(fp_line
			(start 0.7874 0.4064)
			(end -0.7874 0.4064)
			(stroke
				(width 0.1524)
				(type default)
			)
			(layer "F.SilkS")
		)
		(fp_line
			(start -0.67945 -0.305054)
			(end -0.12065 -0.305054)
			(stroke
				(width 0.1)
				(type default)
			)
			(layer "F.Fab")
		)
		(fp_line
			(start -0.67945 0.3048)
			(end -0.67945 -0.305054)
			(stroke
				(width 0.1)
				(type default)
			)
			(layer "F.Fab")
		)
		(fp_line
			(start -0.12065 -0.305054)
			(end -0.12065 -0.2794)
			(stroke
				(width 0.1)
				(type default)
			)
			(layer "F.Fab")
		)
		(fp_line
			(start -0.12065 -0.2794)
			(end 0.12065 -0.2794)
			(stroke
				(width 0.1)
				(type default)
			)
			(layer "F.Fab")
		)
		(fp_line
			(start -0.12065 0.2794)
			(end -0.12065 0.3048)
			(stroke
				(width 0.1)
				(type default)
			)
			(layer "F.Fab")
		)
		(fp_line
			(start -0.12065 0.3048)
			(end -0.67945 0.3048)
			(stroke
				(width 0.1)
				(type default)
			)
			(layer "F.Fab")
		)
		(fp_line
			(start 0.120396 0.2794)
			(end -0.12065 0.2794)
			(stroke
				(width 0.1)
				(type default)
			)
			(layer "F.Fab")
		)
		(fp_line
			(start 0.120396 0.3048)
			(end 0.120396 0.2794)
			(stroke
				(width 0.1)
				(type default)
			)
			(layer "F.Fab")
		)
		(fp_line
			(start 0.12065 -0.3048)
			(end 0.67945 -0.3048)
			(stroke
				(width 0.1)
				(type default)
			)
			(layer "F.Fab")
		)
		(fp_line
			(start 0.12065 -0.2794)
			(end 0.12065 -0.3048)
			(stroke
				(width 0.1)
				(type default)
			)
			(layer "F.Fab")
		)
		(fp_line
			(start 0.67945 -0.3048)
			(end 0.67945 0.3048)
			(stroke
				(width 0.1)
				(type default)
			)
			(layer "F.Fab")
		)
		(fp_line
			(start 0.67945 0.3048)
			(end 0.120396 0.3048)
			(stroke
				(width 0.1)
				(type default)
			)
			(layer "F.Fab")
		)
		(pad "1" smd circle
			(at -0.40005 0)
			(size 0 0)
			(layers "F.Cu" "F.Mask" "F.Paste")
			(net "SSD8_ADC_ALERT_N")
		)
		(pad "2" smd circle
			(at 0.40005 0)
			(size 0 0)
			(layers "F.Cu" "F.Mask" "F.Paste")
			(net "SSD_8_15_ADC_ALERT_N")
		)
	)
)
